# S9S_MB_2U (Grand Teton) — schematic netlist excerpt (pin names and nets, part order shuffled) for the footprints in the layout excerpt that follows; sources: Cadence DE-HDL packaged netlist, KiCad conversion of 03242023_DA0F0TMBIJ0_F0T_Motherboard_J_brd_V01_OCP.brd

R1815  Q_RES  0 5% CHIP  pkg 0402LF  page 240 : A = FM_BMC_PWRBTN_OUT_N ; B = FM_BMC_PWRBTN_OUT_R_N
PC1269  Q_CAP  22UF 4V 20% X6S  pkg C0805  page 299 : A = PVPP_HBM_CPU1 ; B = GND
R4291  Q_RES  4.7K 1% EMPTY  pkg 0402LF  page 169 : A = P3V3_AUX ; B = FM_USB3_1_EN_N

(kicad_pcb
	(version 20260206)
	(generator "pcbnew")
	(generator_version "10.0")
	(general
		(thickness 1.6)
		(legacy_teardrops no)
	)
	(paper "A4")
	(title_block
		(title "03242023_DA0F0TMBIJ0_F0T_Motherboard_J_brd_V01_OCP.brd")
		(comment 1 "Grand Teton / footprints 5731-5733 of 6105")
	)
	(layers
		(0 "F.Cu" signal "TOP")
		(4 "In1.Cu" signal "GND")
		(6 "In2.Cu" signal "IN1")
		(8 "In3.Cu" signal "GND1")
		(10 "In4.Cu" signal "IN2")
		(12 "In5.Cu" signal "GND2")
		(14 "In6.Cu" signal "IN3")
		(16 "In7.Cu" signal "GND3")
		(18 "In8.Cu" signal "VCC")
		(20 "In9.Cu" signal "VCC1")
		(22 "In10.Cu" signal "GND4")
		(24 "In11.Cu" signal "IN4")
		(26 "In12.Cu" signal "GND5")
		(28 "In13.Cu" signal "IN5")
		(30 "In14.Cu" signal "GND6")
		(32 "In15.Cu" signal "IN6")
		(34 "In16.Cu" signal "GND7")
		(2 "B.Cu" signal "BOTTOM")
		(9 "F.Adhes" user "F.Adhesive")
		(11 "B.Adhes" user "B.Adhesive")
		(13 "F.Paste" user "Package Geometry/Pastemask Top")
		(15 "B.Paste" user "Package Geometry/Pastemask Bottom")
		(5 "F.SilkS" user "Ref Des/Silkscreen Top")
		(7 "B.SilkS" user "Ref Des/Silkscreen Bottom")
		(1 "F.Mask" user "Board Geometry/Soldermask Top")
		(3 "B.Mask" user "Board Geometry/Soldermask Bottom")
		(17 "Dwgs.User" user "User.Drawings")
		(19 "Cmts.User" user "User.Comments")
		(21 "Eco1.User" user "User.Eco1")
		(23 "Eco2.User" user "User.Eco2")
		(25 "Edge.Cuts" user "Board Geometry/Outline")
		(27 "Margin" user)
		(31 "F.CrtYd" user "Package Geometry/Place Bound Top")
		(29 "B.CrtYd" user "Package Geometry/Place Bound Bottom")
		(35 "F.Fab" user "Ref Des/Assembly Top")
		(33 "B.Fab" user "Ref Des/Assembly Bottom")
	)
	(footprint ""
		(layer "B.Cu")
		(at 126.87554 -20.985988 -90)
		(property "Reference" "R4291"
			(at 0 0 90)
			(layer "B.SilkS")
			(hide yes)
			(effects
				(font
					(size 1.27 1.27)
				)
				(justify mirror)
			)
		)
		(property "Value" ""
			(at 0 0 90)
			(layer "B.Fab")
			(effects
				(font
					(size 1.27 1.27)
				)
				(justify mirror)
			)
		)
		(duplicate_pad_numbers_are_jumpers no)
		(fp_line
			(start -0.7874 0.4064)
			(end 0.7874 0.4064)
			(stroke
				(width 0.1524)
				(type default)
			)
			(layer "B.SilkS")
		)
		(fp_line
			(start 0.7874 0.4064)
			(end 0.7874 -0.4064)
			(stroke
				(width 0.1524)
				(type default)
			)
			(layer "B.SilkS")
		)
		(fp_line
			(start -0.7874 -0.4064)
			(end -0.7874 0.4064)
			(stroke
				(width 0.1524)
				(type default)
			)
			(layer "B.SilkS")
		)
		(fp_line
			(start 0.7874 -0.4064)
			(end -0.7874 -0.4064)
			(stroke
				(width 0.1524)
				(type default)
			)
			(layer "B.SilkS")
		)
		(fp_line
			(start -0.67945 0.3048)
			(end -0.120396 0.3048)
			(stroke
				(width 0.1)
				(type default)
			)
			(layer "B.Fab")
		)
		(fp_line
			(start -0.120396 0.3048)
			(end -0.120396 0.2794)
			(stroke
				(width 0.1)
				(type default)
			)
			(layer "B.Fab")
		)
		(fp_line
			(start 0.12065 0.3048)
			(end 0.67945 0.3048)
			(stroke
				(width 0.1)
				(type default)
			)
			(layer "B.Fab")
		)
		(fp_line
			(start 0.67945 0.3048)
			(end 0.67945 -0.305054)
			(stroke
				(width 0.1)
				(type default)
			)
			(layer "B.Fab")
		)
		(fp_line
			(start -0.120396 0.2794)
			(end 0.12065 0.2794)
			(stroke
				(width 0.1)
				(type default)
			)
			(layer "B.Fab")
		)
		(fp_line
			(start 0.12065 0.2794)
			(end 0.12065 0.3048)
			(stroke
				(width 0.1)
				(type default)
			)
			(layer "B.Fab")
		)
		(fp_line
			(start -0.12065 -0.2794)
			(end -0.12065 -0.3048)
			(stroke
				(width 0.1)
				(type default)
			)
			(layer "B.Fab")
		)
		(fp_line
			(start 0.12065 -0.2794)
			(end -0.12065 -0.2794)
			(stroke
				(width 0.1)
				(type default)
			)
			(layer "B.Fab")
		)
		(fp_line
			(start -0.67945 -0.3048)
			(end -0.67945 0.3048)
			(stroke
				(width 0.1)
				(type default)
			)
			(layer "B.Fab")
		)
		(fp_line
			(start -0.12065 -0.3048)
			(end -0.67945 -0.3048)
			(stroke
				(width 0.1)
				(type default)
			)
			(layer "B.Fab")
		)
		(fp_line
			(start 0.12065 -0.305054)
			(end 0.12065 -0.2794)
			(stroke
				(width 0.1)
				(type default)
			)
			(layer "B.Fab")
		)
		(fp_line
			(start 0.67945 -0.305054)
			(end 0.12065 -0.305054)
			(stroke
				(width 0.1)
				(type default)
			)
			(layer "B.Fab")
		)
		(pad "1" smd circle
			(at 0.40005 0 90)
			(size 0 0)
			(layers "B.Cu" "B.Mask" "B.Paste")
			(net "P3V3_AUX")
		)
		(pad "2" smd circle
			(at -0.40005 0 90)
			(size 0 0)
			(layers "B.Cu" "B.Mask" "B.Paste")
			(net "FM_USB3_1_EN_N")
		)
	)
	(footprint ""
		(layer "B.Cu")
		(at 127.907542 -366.723168 90)
		(property "Reference" "PC1269"
			(at 0 0 90)
			(layer "B.SilkS")
			(hide yes)
			(effects
				(font
					(size 1.27 1.27)
				)
				(justify mirror)
			)
		)
		(property "Value" ""
			(at 0 0 90)
			(layer "B.Fab")
			(effects
				(font
					(size 1.27 1.27)
				)
				(justify mirror)
			)
		)
		(duplicate_pad_numbers_are_jumpers no)
		(fp_line
			(start 1.524 -0.762)
			(end -1.524 -0.762)
			(stroke
				(width 0.1524)
				(type default)
			)
			(layer "B.SilkS")
		)
		(fp_line
			(start -1.524 -0.762)
			(end -1.524 0.762)
			(stroke
				(width 0.1524)
				(type default)
			)
			(layer "B.SilkS")
		)
		(fp_line
			(start 1.524 0.762)
			(end 1.524 -0.762)
			(stroke
				(width 0.1524)
				(type default)
			)
			(layer "B.SilkS")
		)
		(fp_line
			(start -1.524 0.762)
			(end 1.524 0.762)
			(stroke
				(width 0.1524)
				(type default)
			)
			(layer "B.SilkS")
		)
		(fp_line
			(start 1.1049 -0.724916)
			(end 1.1049 0.724916)
			(stroke
				(width 0.1)
				(type default)
			)
			(layer "B.Fab")
		)
		(fp_line
			(start -1.1049 -0.724916)
			(end 1.1049 -0.724916)
			(stroke
				(width 0.1)
				(type default)
			)
			(layer "B.Fab")
		)
		(fp_line
			(start 1.1049 0.724916)
			(end -1.1049 0.724916)
			(stroke
				(width 0.1)
				(type default)
			)
			(layer "B.Fab")
		)
		(fp_line
			(start -1.1049 0.724916)
			(end -1.1049 -0.724916)
			(stroke
				(width 0.1)
				(type default)
			)
			(layer "B.Fab")
		)
		(pad "1" smd rect
			(at 0.889 0 90)
			(size 1.016 1.27)
			(layers "B.Cu" "B.Mask" "B.Paste")
			(net "PVPP_HBM_CPU1")
		)
		(pad "2" smd rect
			(at -0.889 0 90)
			(size 1.016 1.27)
			(layers "B.Cu" "B.Mask" "B.Paste")
			(net "GND")
		)
	)
	(footprint ""
		(layer "B.Cu")
		(at 143.0274 -13.762228 90)
		(property "Reference" "R1815"
			(at 0 0 90)
			(layer "B.SilkS")
			(hide yes)
			(effects
				(font
					(size 1.27 1.27)
				)
				(justify mirror)
			)
		)
		(property "Value" ""
			(at 0 0 90)
			(layer "B.Fab")
			(effects
				(font
					(size 1.27 1.27)
				)
				(justify mirror)
			)
		)
		(duplicate_pad_numbers_are_jumpers no)
		(fp_line
			(start 0.7874 -0.4064)
			(end -0.7874 -0.4064)
			(stroke
				(width 0.1524)
				(type default)
			)
			(layer "B.SilkS")
		)
		(fp_line
			(start -0.7874 -0.4064)
			(end -0.7874 0.4064)
			(stroke
				(width 0.1524)
				(type default)
			)
			(layer "B.SilkS")
		)
		(fp_line
			(start 0.7874 0.4064)
			(end 0.7874 -0.4064)
			(stroke
				(width 0.1524)
				(type default)
			)
			(layer "B.SilkS")
		)
		(fp_line
			(start -0.7874 0.4064)
			(end 0.7874 0.4064)
			(stroke
				(width 0.1524)
				(type default)
			)
			(layer "B.SilkS")
		)
		(fp_line
			(start 0.67945 -0.305054)
			(end 0.12065 -0.305054)
			(stroke
				(width 0.1)
				(type default)
			)
			(layer "B.Fab")
		)
		(fp_line
			(start 0.12065 -0.305054)
			(end 0.12065 -0.2794)
			(stroke
				(width 0.1)
				(type default)
			)
			(layer "B.Fab")
		)
		(fp_line
			(start -0.12065 -0.3048)
			(end -0.67945 -0.3048)
			(stroke
				(width 0.1)
				(type default)
			)
			(layer "B.Fab")
		)
		(fp_line
			(start -0.67945 -0.3048)
			(end -0.67945 0.3048)
			(stroke
				(width 0.1)
				(type default)
			)
			(layer "B.Fab")
		)
		(fp_line
			(start 0.12065 -0.2794)
			(end -0.12065 -0.2794)
			(stroke
				(width 0.1)
				(type default)
			)
			(layer "B.Fab")
		)
		(fp_line
			(start -0.12065 -0.2794)
			(end -0.12065 -0.3048)
			(stroke
				(width 0.1)
				(type default)
			)
			(layer "B.Fab")
		)
		(fp_line
			(start 0.12065 0.2794)
			(end 0.12065 0.3048)
			(stroke
				(width 0.1)
				(type default)
			)
			(layer "B.Fab")
		)
		(fp_line
			(start -0.120396 0.2794)
			(end 0.12065 0.2794)
			(stroke
				(width 0.1)
				(type default)
			)
			(layer "B.Fab")
		)
		(fp_line
			(start 0.67945 0.3048)
			(end 0.67945 -0.305054)
			(stroke
				(width 0.1)
				(type default)
			)
			(layer "B.Fab")
		)
		(fp_line
			(start 0.12065 0.3048)
			(end 0.67945 0.3048)
			(stroke
				(width 0.1)
				(type default)
			)
			(layer "B.Fab")
		)
		(fp_line
			(start -0.120396 0.3048)
			(end -0.120396 0.2794)
			(stroke
				(width 0.1)
				(type default)
			)
			(layer "B.Fab")
		)
		(fp_line
			(start -0.67945 0.3048)
			(end -0.120396 0.3048)
			(stroke
				(width 0.1)
				(type default)
			)
			(layer "B.Fab")
		)
		(pad "1" smd circle
			(at 0.40005 0 270)
			(size 0 0)
			(layers "B.Cu" "B.Mask" "B.Paste")
			(net "FM_BMC_PWRBTN_OUT_N")
		)
		(pad "2" smd circle
			(at -0.40005 0 270)
			(size 0 0)
			(layers "B.Cu" "B.Mask" "B.Paste")
			(net "FM_BMC_PWRBTN_OUT_R_N")
		)
	)
)
